(kicad_pcb
	(version 20260206)
	(generator "pcbnew")
	(generator_version "10.0")
	(general
		(thickness 1.6)
		(legacy_teardrops no)
	)
	(paper "A4")
	(title_block
		(title "Bryce Canyon_R.DPB_16317-1_OCP.brd")
		(comment 1 "Bryce Canyon / footprints 399-405 of 2099")
	)
	(layers
		(0 "F.Cu" signal "TOP")
		(4 "In1.Cu" signal "L2GND")
		(6 "In2.Cu" signal "L3")
		(8 "In3.Cu" signal "L4VCC")
		(10 "In4.Cu" signal "L5VCC")
		(12 "In5.Cu" signal "L6")
		(14 "In6.Cu" signal "L7GND")
		(2 "B.Cu" signal "BOTTOM")
		(9 "F.Adhes" user "F.Adhesive")
		(11 "B.Adhes" user "B.Adhesive")
		(13 "F.Paste" user "Package Geometry/Pastemask Top")
		(15 "B.Paste" user "Package Geometry/Pastemask Bottom")
		(5 "F.SilkS" user "Ref Des/Silkscreen Top")
		(7 "B.SilkS" user "Ref Des/Silkscreen Bottom")
		(1 "F.Mask" user "Board Geometry/Soldermask Top")
		(3 "B.Mask" user "Board Geometry/Soldermask Bottom")
		(17 "Dwgs.User" user "User.Drawings")
		(19 "Cmts.User" user "User.Comments")
		(21 "Eco1.User" user "User.Eco1")
		(23 "Eco2.User" user "User.Eco2")
		(25 "Edge.Cuts" user "Board Geometry/Outline")
		(27 "Margin" user)
		(31 "F.CrtYd" user "Package Geometry/Place Bound Top")
		(29 "B.CrtYd" user "Package Geometry/Place Bound Bottom")
		(35 "F.Fab" user "Ref Des/Assembly Top")
		(33 "B.Fab" user "Ref Des/Assembly Bottom")
	)
	(footprint ""
		(layer "F.Cu")
		(at 35.306 -262.128 90)
		(property "Reference" "C505"
			(at 0 0 90)
			(layer "F.SilkS")
			(hide yes)
			(effects
				(font
					(size 1.27 1.27)
				)
			)
		)
		(property "Value" "SCD01U50V2KX-1GP"
			(at 1.1811 -2.7051 90)
			(unlocked yes)
			(layer "F.Fab")
			(hide yes)
			(effects
				(font
					(size 1.016 1.016)
					(thickness 0.1524)
				)
			)
		)
		(property "Device Type" "C402H22"
			(at 1.1811 -4.2291 90)
			(unlocked yes)
			(layer "F.Fab")
			(hide yes)
			(effects
				(font
					(size 1.016 1.016)
					(thickness 0.1524)
				)
			)
		)
		(duplicate_pad_numbers_are_jumpers no)
		(fp_rect
			(start -0.4318 0.9525)
			(end 0.4318 -0.9525)
			(stroke
				(width 0)
				(type default)
			)
			(fill no)
			(layer "F.CrtYd")
		)
		(fp_rect
			(start -0.4318 0.9525)
			(end 0.4318 -0.9525)
			(stroke
				(width 0)
				(type default)
			)
			(fill no)
			(layer "F.Fab")
		)
		(pad "1" smd custom
			(at 0 -0.4445 90)
			(size 0.1524 0.1524)
			(layers "F.Cu" "F.Mask" "F.Paste")
			(net "HDD_PRSNT_0")
			(options
				(clearance outline)
				(anchor circle)
			)
			(primitives
				(gr_poly
					(pts
						(arc
							(start 0.3048 -0.2032)
							(mid 0.275042 -0.275042)
							(end 0.2032 -0.3048)
						)
						(arc
							(start -0.2032 -0.3048)
							(mid -0.275042 -0.275042)
							(end -0.3048 -0.2032)
						)
						(arc
							(start -0.3048 0.2032)
							(mid -0.275042 0.275042)
							(end -0.2032 0.3048)
						)
						(arc
							(start 0.2032 0.3048)
							(mid 0.275042 0.275042)
							(end 0.3048 0.2032)
						)
					)
					(width 0)
					(fill yes)
				)
			)
		)
		(pad "2" smd custom
			(at 0 0.4445 90)
			(size 0.1524 0.1524)
			(layers "F.Cu" "F.Mask" "F.Paste")
			(net "GND")
			(options
				(clearance outline)
				(anchor circle)
			)
			(primitives
				(gr_poly
					(pts
						(arc
							(start 0.3048 -0.2032)
							(mid 0.275042 -0.275042)
							(end 0.2032 -0.3048)
						)
						(arc
							(start -0.2032 -0.3048)
							(mid -0.275042 -0.275042)
							(end -0.3048 -0.2032)
						)
						(arc
							(start -0.3048 0.2032)
							(mid -0.275042 0.275042)
							(end -0.2032 0.3048)
						)
						(arc
							(start 0.2032 0.3048)
							(mid 0.275042 0.275042)
							(end 0.3048 0.2032)
						)
					)
					(width 0)
					(fill yes)
				)
			)
		)
	)
	(footprint ""
		(layer "F.Cu")
		(at 329.819 -275.336 180)
		(property "Reference" "C114"
			(at 0 0 180)
			(layer "F.SilkS")
			(hide yes)
			(effects
				(font
					(size 1.27 1.27)
				)
			)
		)
		(property "Value" "SC1U25V3KX-GP"
			(at 0 -2.8194 180)
			(unlocked yes)
			(layer "F.Fab")
			(hide yes)
			(effects
				(font
					(size 1.016 1.016)
					(thickness 0.1524)
				)
			)
		)
		(property "Device Type" "C603H36"
			(at 0 -4.3434 180)
			(unlocked yes)
			(layer "F.Fab")
			(hide yes)
			(effects
				(font
					(size 1.016 1.016)
					(thickness 0.1524)
				)
			)
		)
		(duplicate_pad_numbers_are_jumpers no)
		(fp_line
			(start 0.508 0)
			(end -0.508 0)
			(stroke
				(width 0.2032)
				(type default)
			)
			(layer "F.SilkS")
		)
		(fp_rect
			(start -0.5842 1.3335)
			(end 0.5842 -1.3335)
			(stroke
				(width 0)
				(type default)
			)
			(fill no)
			(layer "F.CrtYd")
		)
		(fp_rect
			(start -0.5842 1.3335)
			(end 0.5842 -1.3335)
			(stroke
				(width 0)
				(type default)
			)
			(fill no)
			(layer "F.Fab")
		)
		(pad "1" smd custom
			(at 0 -0.762 180)
			(size 0.2159 0.2159)
			(layers "F.Cu" "F.Mask" "F.Paste")
			(net "P12V_HDD6")
			(options
				(clearance outline)
				(anchor circle)
			)
			(primitives
				(gr_poly
					(pts
						(arc
							(start -0.3302 -0.4318)
							(mid -0.402042 -0.402042)
							(end -0.4318 -0.3302)
						)
						(arc
							(start -0.4318 0.3302)
							(mid -0.402042 0.402042)
							(end -0.3302 0.4318)
						)
						(arc
							(start 0.3302 0.4318)
							(mid 0.402042 0.402042)
							(end 0.4318 0.3302)
						)
						(arc
							(start 0.4318 -0.3302)
							(mid 0.402042 -0.402042)
							(end 0.3302 -0.4318)
						)
					)
					(width 0)
					(fill yes)
				)
			)
		)
		(pad "2" smd custom
			(at 0 0.762 180)
			(size 0.2159 0.2159)
			(layers "F.Cu" "F.Mask" "F.Paste")
			(net "GND")
			(options
				(clearance outline)
				(anchor circle)
			)
			(primitives
				(gr_poly
					(pts
						(arc
							(start -0.3302 -0.4318)
							(mid -0.402042 -0.402042)
							(end -0.4318 -0.3302)
						)
						(arc
							(start -0.4318 0.3302)
							(mid -0.402042 0.402042)
							(end -0.3302 0.4318)
						)
						(arc
							(start 0.3302 0.4318)
							(mid 0.402042 0.402042)
							(end 0.4318 0.3302)
						)
						(arc
							(start 0.4318 -0.3302)
							(mid 0.402042 -0.402042)
							(end 0.3302 -0.4318)
						)
					)
					(width 0)
					(fill yes)
				)
			)
		)
	)
	(footprint ""
		(layer "F.Cu")
		(at 371.801644 -212.390228 -90)
		(property "Reference" "R277"
			(at 0 0 270)
			(layer "F.SilkS")
			(hide yes)
			(effects
				(font
					(size 1.27 1.27)
				)
			)
		)
		(property "Value" "4K7R2F-GP"
			(at 0.064008 -3.993896 270)
			(unlocked yes)
			(layer "F.Fab")
			(hide yes)
			(effects
				(font
					(size 1.016 1.016)
					(thickness 0.1524)
				)
			)
		)
		(property "Device Type" "R402H16"
			(at 0.064008 -5.517896 270)
			(unlocked yes)
			(layer "F.Fab")
			(hide yes)
			(effects
				(font
					(size 1.016 1.016)
					(thickness 0.1524)
				)
			)
		)
		(duplicate_pad_numbers_are_jumpers no)
		(fp_line
			(start -0.508 -0.9398)
			(end -0.508 0.9398)
			(stroke
				(width 0.1524)
				(type default)
			)
			(layer "F.SilkS")
		)
		(fp_line
			(start 0.508 -0.9398)
			(end -0.508 -0.9398)
			(stroke
				(width 0.1524)
				(type default)
			)
			(layer "F.SilkS")
		)
		(fp_rect
			(start -0.508 0.9398)
			(end 0.508 -0.9398)
			(stroke
				(width 0)
				(type default)
			)
			(fill no)
			(layer "F.CrtYd")
		)
		(fp_rect
			(start -0.508 0.9398)
			(end 0.508 -0.9398)
			(stroke
				(width 0)
				(type default)
			)
			(fill no)
			(layer "F.Fab")
		)
		(pad "1" smd custom
			(at 0 -0.4445 270)
			(size 0.1397 0.1397)
			(layers "F.Cu" "F.Mask" "F.Paste")
			(net "DRIVE_B_8_ACT")
			(options
				(clearance outline)
				(anchor circle)
			)
			(primitives
				(gr_poly
					(pts
						(arc
							(start -0.1778 -0.2794)
							(mid -0.249642 -0.249642)
							(end -0.2794 -0.1778)
						)
						(arc
							(start -0.2794 0.1778)
							(mid -0.249642 0.249642)
							(end -0.1778 0.2794)
						)
						(arc
							(start 0.1778 0.2794)
							(mid 0.249642 0.249642)
							(end 0.2794 0.1778)
						)
						(arc
							(start 0.2794 -0.1778)
							(mid 0.249642 -0.249642)
							(end 0.1778 -0.2794)
						)
					)
					(width 0)
					(fill yes)
				)
			)
		)
		(pad "2" smd custom
			(at 0 0.4445 270)
			(size 0.1397 0.1397)
			(layers "F.Cu" "F.Mask" "F.Paste")
			(net "GND")
			(options
				(clearance outline)
				(anchor circle)
			)
			(primitives
				(gr_poly
					(pts
						(arc
							(start -0.1778 -0.2794)
							(mid -0.249642 -0.249642)
							(end -0.2794 -0.1778)
						)
						(arc
							(start -0.2794 0.1778)
							(mid -0.249642 0.249642)
							(end -0.1778 0.2794)
						)
						(arc
							(start 0.1778 0.2794)
							(mid 0.249642 0.249642)
							(end 0.2794 0.1778)
						)
						(arc
							(start 0.2794 -0.1778)
							(mid 0.249642 -0.249642)
							(end 0.1778 -0.2794)
						)
					)
					(width 0)
					(fill yes)
				)
			)
		)
	)
	(footprint ""
		(layer "F.Cu")
		(at 181.483 -33.274)
		(property "Reference" "R736"
			(at 0 0 0)
			(layer "F.SilkS")
			(hide yes)
			(effects
				(font
					(size 1.27 1.27)
				)
			)
		)
		(property "Value" "2R6F-GP"
			(at -0.0508 -4.8514 0)
			(unlocked yes)
			(layer "F.Fab")
			(hide yes)
			(effects
				(font
					(size 1.016 1.016)
					(thickness 0.1524)
				)
			)
		)
		(property "Device Type" "R1206H26"
			(at 0 -6.3754 0)
			(unlocked yes)
			(layer "F.Fab")
			(hide yes)
			(effects
				(font
					(size 1.016 1.016)
					(thickness 0.1524)
				)
			)
		)
		(duplicate_pad_numbers_are_jumpers no)
		(fp_line
			(start -1.016 -2.2352)
			(end 1.016 -2.2352)
			(stroke
				(width 0.1524)
				(type default)
			)
			(layer "F.SilkS")
		)
		(fp_line
			(start -1.016 2.2352)
			(end -1.016 -2.2352)
			(stroke
				(width 0.1524)
				(type default)
			)
			(layer "F.SilkS")
		)
		(fp_line
			(start 1.016 -2.2352)
			(end 1.016 2.2352)
			(stroke
				(width 0.1524)
				(type default)
			)
			(layer "F.SilkS")
		)
		(fp_line
			(start 1.016 2.2352)
			(end -1.016 2.2352)
			(stroke
				(width 0.1524)
				(type default)
			)
			(layer "F.SilkS")
		)
		(fp_rect
			(start -1.0922 2.3114)
			(end 1.0922 -2.3114)
			(stroke
				(width 0)
				(type default)
			)
			(fill no)
			(layer "F.CrtYd")
		)
		(fp_poly
			(pts
				(xy -1.0922 -2.3114) (xy 1.0922 -2.3114) (xy 1.0922 2.3114) (xy -1.0922 2.3114)
			)
			(stroke
				(width 0)
				(type default)
			)
			(fill no)
			(layer "F.Fab")
		)
		(pad "1" smd rect
			(at 0 -1.397)
			(size 1.651 1.27)
			(layers "F.Cu" "F.Mask" "F.Paste")
			(net "P5V_HDD29")
		)
		(pad "2" smd rect
			(at 0 1.397)
			(size 1.651 1.27)
			(layers "F.Cu" "F.Mask" "F.Paste")
			(net "5V_PRE_29")
		)
	)
	(footprint ""
		(layer "F.Cu")
		(at 471.805 -138.049 90)
		(property "Reference" "R606"
			(at 0 0 90)
			(layer "F.SilkS")
			(hide yes)
			(effects
				(font
					(size 1.27 1.27)
				)
			)
		)
		(property "Value" "4K7R2J-2-GP"
			(at 0.064008 -3.993896 90)
			(unlocked yes)
			(layer "F.Fab")
			(hide yes)
			(effects
				(font
					(size 1.016 1.016)
					(thickness 0.1524)
				)
			)
		)
		(property "Device Type" "R402H16"
			(at 0.064008 -5.517896 90)
			(unlocked yes)
			(layer "F.Fab")
			(hide yes)
			(effects
				(font
					(size 1.016 1.016)
					(thickness 0.1524)
				)
			)
		)
		(duplicate_pad_numbers_are_jumpers no)
		(fp_line
			(start 0.508 -0.9398)
			(end -0.508 -0.9398)
			(stroke
				(width 0.1524)
				(type default)
			)
			(layer "F.SilkS")
		)
		(fp_line
			(start -0.508 -0.9398)
			(end -0.508 0.9398)
			(stroke
				(width 0.1524)
				(type default)
			)
			(layer "F.SilkS")
		)
		(fp_rect
			(start -0.508 0.9398)
			(end 0.508 -0.9398)
			(stroke
				(width 0)
				(type default)
			)
			(fill no)
			(layer "F.CrtYd")
		)
		(fp_rect
			(start -0.508 0.9398)
			(end 0.508 -0.9398)
			(stroke
				(width 0)
				(type default)
			)
			(fill no)
			(layer "F.Fab")
		)
		(pad "1" smd custom
			(at 0 -0.4445 90)
			(size 0.1397 0.1397)
			(layers "F.Cu" "F.Mask" "F.Paste")
			(net "P12V_B")
			(options
				(clearance outline)
				(anchor circle)
			)
			(primitives
				(gr_poly
					(pts
						(arc
							(start -0.1778 -0.2794)
							(mid -0.249642 -0.249642)
							(end -0.2794 -0.1778)
						)
						(arc
							(start -0.2794 0.1778)
							(mid -0.249642 0.249642)
							(end -0.1778 0.2794)
						)
						(arc
							(start 0.1778 0.2794)
							(mid 0.249642 0.249642)
							(end 0.2794 0.1778)
						)
						(arc
							(start 0.2794 -0.1778)
							(mid 0.249642 -0.249642)
							(end 0.1778 -0.2794)
						)
					)
					(width 0)
					(fill yes)
				)
			)
		)
		(pad "2" smd custom
			(at 0 0.4445 90)
			(size 0.1397 0.1397)
			(layers "F.Cu" "F.Mask" "F.Paste")
			(net "SW_HDD_P23")
			(options
				(clearance outline)
				(anchor circle)
			)
			(primitives
				(gr_poly
					(pts
						(arc
							(start -0.1778 -0.2794)
							(mid -0.249642 -0.249642)
							(end -0.2794 -0.1778)
						)
						(arc
							(start -0.2794 0.1778)
							(mid -0.249642 0.249642)
							(end -0.1778 0.2794)
						)
						(arc
							(start 0.1778 0.2794)
							(mid 0.249642 0.249642)
							(end 0.2794 0.1778)
						)
						(arc
							(start 0.2794 -0.1778)
							(mid 0.249642 -0.249642)
							(end 0.1778 -0.2794)
						)
					)
					(width 0)
					(fill yes)
				)
			)
		)
	)
	(footprint ""
		(layer "F.Cu")
		(at 191.219328 -370.844826)
		(property "Reference" "R1306"
			(at 0 0 0)
			(layer "F.SilkS")
			(hide yes)
			(effects
				(font
					(size 1.27 1.27)
				)
			)
		)
		(property "Value" "4K7R2F-GP"
			(at 0.064008 -3.993896 0)
			(unlocked yes)
			(layer "F.Fab")
			(hide yes)
			(effects
				(font
					(size 1.016 1.016)
					(thickness 0.1524)
				)
			)
		)
		(property "Device Type" "R402H16"
			(at 0.064008 -5.517896 0)
			(unlocked yes)
			(layer "F.Fab")
			(hide yes)
			(effects
				(font
					(size 1.016 1.016)
					(thickness 0.1524)
				)
			)
		)
		(duplicate_pad_numbers_are_jumpers no)
		(fp_line
			(start -0.508 -0.9398)
			(end -0.508 0.9398)
			(stroke
				(width 0.1524)
				(type default)
			)
			(layer "F.SilkS")
		)
		(fp_line
			(start 0.508 -0.9398)
			(end -0.508 -0.9398)
			(stroke
				(width 0.1524)
				(type default)
			)
			(layer "F.SilkS")
		)
		(fp_rect
			(start -0.508 0.9398)
			(end 0.508 -0.9398)
			(stroke
				(width 0)
				(type default)
			)
			(fill no)
			(layer "F.CrtYd")
		)
		(fp_rect
			(start -0.508 0.9398)
			(end 0.508 -0.9398)
			(stroke
				(width 0)
				(type default)
			)
			(fill no)
			(layer "F.Fab")
		)
		(pad "1" smd custom
			(at 0 -0.4445)
			(size 0.1397 0.1397)
			(layers "F.Cu" "F.Mask" "F.Paste")
			(net "FAN_YELLOW_LED1")
			(options
				(clearance outline)
				(anchor circle)
			)
			(primitives
				(gr_poly
					(pts
						(arc
							(start -0.1778 -0.2794)
							(mid -0.249642 -0.249642)
							(end -0.2794 -0.1778)
						)
						(arc
							(start -0.2794 0.1778)
							(mid -0.249642 0.249642)
							(end -0.1778 0.2794)
						)
						(arc
							(start 0.1778 0.2794)
							(mid 0.249642 0.249642)
							(end 0.2794 0.1778)
						)
						(arc
							(start 0.2794 -0.1778)
							(mid 0.249642 -0.249642)
							(end 0.1778 -0.2794)
						)
					)
					(width 0)
					(fill yes)
				)
			)
		)
		(pad "2" smd custom
			(at 0 0.4445)
			(size 0.1397 0.1397)
			(layers "F.Cu" "F.Mask" "F.Paste")
			(net "FAN_LED1_D2")
			(options
				(clearance outline)
				(anchor circle)
			)
			(primitives
				(gr_poly
					(pts
						(arc
							(start -0.1778 -0.2794)
							(mid -0.249642 -0.249642)
							(end -0.2794 -0.1778)
						)
						(arc
							(start -0.2794 0.1778)
							(mid -0.249642 0.249642)
							(end -0.1778 0.2794)
						)
						(arc
							(start 0.1778 0.2794)
							(mid 0.249642 0.249642)
							(end 0.2794 0.1778)
						)
						(arc
							(start 0.2794 -0.1778)
							(mid 0.249642 -0.249642)
							(end 0.1778 -0.2794)
						)
					)
					(width 0)
					(fill yes)
				)
			)
		)
	)
	(footprint ""
		(layer "F.Cu")
		(at 49.04486 -113.128806)
		(property "Reference" "R1120"
			(at 0 0 0)
			(layer "F.SilkS")
			(hide yes)
			(effects
				(font
					(size 1.27 1.27)
				)
			)
		)
		(property "Value" "0R3J-0-U-GP"
			(at -0.0254 -2.5146 0)
			(unlocked yes)
			(layer "F.Fab")
			(hide yes)
			(effects
				(font
					(size 1.016 1.016)
					(thickness 0.1524)
				)
			)
		)
		(property "Device Type" "R603H22"
			(at -0.0254 -4.0386 0)
			(unlocked yes)
			(layer "F.Fab")
			(hide yes)
			(effects
				(font
					(size 1.016 1.016)
					(thickness 0.1524)
				)
			)
		)
		(duplicate_pad_numbers_are_jumpers no)
		(fp_line
			(start -0.4826 0)
			(end -0.2032 0)
			(stroke
				(width 0.2032)
				(type default)
			)
			(layer "F.SilkS")
		)
		(fp_line
			(start 0.2032 0)
			(end 0.4826 0)
			(stroke
				(width 0.2032)
				(type default)
			)
			(layer "F.SilkS")
		)
		(fp_rect
			(start -0.5842 1.3335)
			(end 0.5842 -1.3335)
			(stroke
				(width 0)
				(type default)
			)
			(fill no)
			(layer "F.CrtYd")
		)
		(fp_rect
			(start -0.5842 1.3335)
			(end 0.5842 -1.3335)
			(stroke
				(width 0)
				(type default)
			)
			(fill no)
			(layer "F.Fab")
		)
		(pad "1" smd custom
			(at 0 -0.762)
			(size 0.2159 0.2159)
			(layers "F.Cu" "F.Mask" "F.Paste")
			(net "P5V_B_2_VBST")
			(options
				(clearance outline)
				(anchor circle)
			)
			(primitives
				(gr_poly
					(pts
						(arc
							(start -0.3302 -0.4318)
							(mid -0.402042 -0.402042)
							(end -0.4318 -0.3302)
						)
						(arc
							(start -0.4318 0.3302)
							(mid -0.402042 0.402042)
							(end -0.3302 0.4318)
						)
						(arc
							(start 0.3302 0.4318)
							(mid 0.402042 0.402042)
							(end 0.4318 0.3302)
						)
						(arc
							(start 0.4318 -0.3302)
							(mid 0.402042 -0.402042)
							(end 0.3302 -0.4318)
						)
					)
					(width 0)
					(fill yes)
				)
			)
		)
		(pad "2" smd custom
			(at 0 0.762)
			(size 0.2159 0.2159)
			(layers "F.Cu" "F.Mask" "F.Paste")
			(net "P5V_B_2_VBST_RC")
			(options
				(clearance outline)
				(anchor circle)
			)
			(primitives
				(gr_poly
					(pts
						(arc
							(start -0.3302 -0.4318)
							(mid -0.402042 -0.402042)
							(end -0.4318 -0.3302)
						)
						(arc
							(start -0.4318 0.3302)
							(mid -0.402042 0.402042)
							(end -0.3302 0.4318)
						)
						(arc
							(start 0.3302 0.4318)
							(mid 0.402042 0.402042)
							(end 0.4318 0.3302)
						)
						(arc
							(start 0.4318 -0.3302)
							(mid 0.402042 -0.402042)
							(end 0.3302 -0.4318)
						)
					)
					(width 0)
					(fill yes)
				)
			)
		)
	)
)
